(kicad_pcb
	(version 20260206)
	(generator "pcbnew")
	(generator_version "10.0")
	(general
		(thickness 1.6)
		(legacy_teardrops no)
	)
	(paper "A4")
	(title_block
		(title "04192023_DAF0TMB3IC0_F0TG_MB_C_brd_V02_OCP.brd")
		(comment 1 "Grand Teton / footprints 7894-7900 of 8354")
	)
	(layers
		(0 "F.Cu" signal "TOP")
		(4 "In1.Cu" signal "GND")
		(6 "In2.Cu" signal "IN1")
		(8 "In3.Cu" signal "GND1")
		(10 "In4.Cu" signal "IN2")
		(12 "In5.Cu" signal "GND2")
		(14 "In6.Cu" signal "IN3")
		(16 "In7.Cu" signal "GND3")
		(18 "In8.Cu" signal "VCC")
		(20 "In9.Cu" signal "VCC1")
		(22 "In10.Cu" signal "GND4")
		(24 "In11.Cu" signal "IN4")
		(26 "In12.Cu" signal "GND5")
		(28 "In13.Cu" signal "IN5")
		(30 "In14.Cu" signal "GND6")
		(32 "In15.Cu" signal "IN6")
		(34 "In16.Cu" signal "GND7")
		(2 "B.Cu" signal "BOTTOM")
		(9 "F.Adhes" user "F.Adhesive")
		(11 "B.Adhes" user "B.Adhesive")
		(13 "F.Paste" user "Package Geometry/Pastemask Top")
		(15 "B.Paste" user "Package Geometry/Pastemask Bottom")
		(5 "F.SilkS" user "Ref Des/Silkscreen Top")
		(7 "B.SilkS" user "Ref Des/Silkscreen Bottom")
		(1 "F.Mask" user "Board Geometry/Soldermask Top")
		(3 "B.Mask" user "Board Geometry/Soldermask Bottom")
		(17 "Dwgs.User" user "User.Drawings")
		(19 "Cmts.User" user "User.Comments")
		(21 "Eco1.User" user "User.Eco1")
		(23 "Eco2.User" user "User.Eco2")
		(25 "Edge.Cuts" user "Board Geometry/Outline")
		(27 "Margin" user)
		(31 "F.CrtYd" user "Package Geometry/Place Bound Top")
		(29 "B.CrtYd" user "Package Geometry/Place Bound Bottom")
		(35 "F.Fab" user "Ref Des/Assembly Top")
		(33 "B.Fab" user "Ref Des/Assembly Bottom")
	)
	(footprint ""
		(layer "B.Cu")
		(at 65.12433 -346.788994 90)
		(property "Reference" "PC411_4"
			(at 0 0 90)
			(layer "B.SilkS")
			(hide yes)
			(effects
				(font
					(size 1.27 1.27)
				)
				(justify mirror)
			)
		)
		(property "Value" ""
			(at 0 0 90)
			(layer "B.Fab")
			(effects
				(font
					(size 1.27 1.27)
				)
				(justify mirror)
			)
		)
		(duplicate_pad_numbers_are_jumpers no)
		(fp_line
			(start 1.524 -0.762)
			(end -1.524 -0.762)
			(stroke
				(width 0.1524)
				(type default)
			)
			(layer "B.SilkS")
		)
		(fp_line
			(start -1.524 -0.762)
			(end -1.524 0.762)
			(stroke
				(width 0.1524)
				(type default)
			)
			(layer "B.SilkS")
		)
		(fp_line
			(start 1.524 0.762)
			(end 1.524 -0.762)
			(stroke
				(width 0.1524)
				(type default)
			)
			(layer "B.SilkS")
		)
		(fp_line
			(start -1.524 0.762)
			(end 1.524 0.762)
			(stroke
				(width 0.1524)
				(type default)
			)
			(layer "B.SilkS")
		)
		(fp_line
			(start 1.1049 -0.724916)
			(end 1.1049 0.724916)
			(stroke
				(width 0.1)
				(type default)
			)
			(layer "B.Fab")
		)
		(fp_line
			(start -1.1049 -0.724916)
			(end 1.1049 -0.724916)
			(stroke
				(width 0.1)
				(type default)
			)
			(layer "B.Fab")
		)
		(fp_line
			(start 1.1049 0.724916)
			(end -1.1049 0.724916)
			(stroke
				(width 0.1)
				(type default)
			)
			(layer "B.Fab")
		)
		(fp_line
			(start -1.1049 0.724916)
			(end -1.1049 -0.724916)
			(stroke
				(width 0.1)
				(type default)
			)
			(layer "B.Fab")
		)
		(pad "1" smd rect
			(at 0.889 0 90)
			(size 1.016 1.27)
			(layers "B.Cu" "B.Mask" "B.Paste")
			(net "SW_P12V_AUX_PVDDCR_CPU1_P1_FLT")
		)
		(pad "2" smd rect
			(at -0.889 0 90)
			(size 1.016 1.27)
			(layers "B.Cu" "B.Mask" "B.Paste")
			(net "GND")
		)
	)
	(footprint ""
		(layer "B.Cu")
		(at 421.895778 -177.861722)
		(property "Reference" "TP10"
			(at -0.61468 0.184912 0)
			(unlocked yes)
			(layer "B.SilkS")
			(effects
				(font
					(size 0.7874 0.5842)
					(thickness 0.1524)
				)
				(justify left mirror)
			)
		)
		(property "Value" ""
			(at 0 0 0)
			(layer "B.Fab")
			(effects
				(font
					(size 1.27 1.27)
				)
				(justify mirror)
			)
		)
		(duplicate_pad_numbers_are_jumpers no)
		(pad "1" smd circle
			(at 0 0 180)
			(size 0.6604 0.6604)
			(layers "B.Cu" "B.Mask" "B.Paste")
			(net "VSENSE_PVDDCR_SOC_P0_DP")
		)
	)
	(footprint ""
		(layer "B.Cu")
		(at 241.756692 -422.849548 90)
		(property "Reference" "R2803"
			(at 0 0 90)
			(layer "B.SilkS")
			(hide yes)
			(effects
				(font
					(size 1.27 1.27)
				)
				(justify mirror)
			)
		)
		(property "Value" ""
			(at 0 0 90)
			(layer "B.Fab")
			(effects
				(font
					(size 1.27 1.27)
				)
				(justify mirror)
			)
		)
		(duplicate_pad_numbers_are_jumpers no)
		(fp_line
			(start 0.7874 -0.4064)
			(end -0.7874 -0.4064)
			(stroke
				(width 0.1524)
				(type default)
			)
			(layer "B.SilkS")
		)
		(fp_line
			(start -0.7874 -0.4064)
			(end -0.7874 0.4064)
			(stroke
				(width 0.1524)
				(type default)
			)
			(layer "B.SilkS")
		)
		(fp_line
			(start 0.7874 0.4064)
			(end 0.7874 -0.4064)
			(stroke
				(width 0.1524)
				(type default)
			)
			(layer "B.SilkS")
		)
		(fp_line
			(start -0.7874 0.4064)
			(end 0.7874 0.4064)
			(stroke
				(width 0.1524)
				(type default)
			)
			(layer "B.SilkS")
		)
		(fp_line
			(start 0.67945 -0.305054)
			(end 0.12065 -0.305054)
			(stroke
				(width 0.1)
				(type default)
			)
			(layer "B.Fab")
		)
		(fp_line
			(start 0.12065 -0.305054)
			(end 0.12065 -0.2794)
			(stroke
				(width 0.1)
				(type default)
			)
			(layer "B.Fab")
		)
		(fp_line
			(start -0.12065 -0.3048)
			(end -0.67945 -0.3048)
			(stroke
				(width 0.1)
				(type default)
			)
			(layer "B.Fab")
		)
		(fp_line
			(start -0.67945 -0.3048)
			(end -0.67945 0.3048)
			(stroke
				(width 0.1)
				(type default)
			)
			(layer "B.Fab")
		)
		(fp_line
			(start 0.12065 -0.2794)
			(end -0.12065 -0.2794)
			(stroke
				(width 0.1)
				(type default)
			)
			(layer "B.Fab")
		)
		(fp_line
			(start -0.12065 -0.2794)
			(end -0.12065 -0.3048)
			(stroke
				(width 0.1)
				(type default)
			)
			(layer "B.Fab")
		)
		(fp_line
			(start 0.12065 0.2794)
			(end 0.12065 0.3048)
			(stroke
				(width 0.1)
				(type default)
			)
			(layer "B.Fab")
		)
		(fp_line
			(start -0.120396 0.2794)
			(end 0.12065 0.2794)
			(stroke
				(width 0.1)
				(type default)
			)
			(layer "B.Fab")
		)
		(fp_line
			(start 0.67945 0.3048)
			(end 0.67945 -0.305054)
			(stroke
				(width 0.1)
				(type default)
			)
			(layer "B.Fab")
		)
		(fp_line
			(start 0.12065 0.3048)
			(end 0.67945 0.3048)
			(stroke
				(width 0.1)
				(type default)
			)
			(layer "B.Fab")
		)
		(fp_line
			(start -0.120396 0.3048)
			(end -0.120396 0.2794)
			(stroke
				(width 0.1)
				(type default)
			)
			(layer "B.Fab")
		)
		(fp_line
			(start -0.67945 0.3048)
			(end -0.120396 0.3048)
			(stroke
				(width 0.1)
				(type default)
			)
			(layer "B.Fab")
		)
		(pad "1" smd circle
			(at 0.40005 0 270)
			(size 0 0)
			(layers "B.Cu" "B.Mask" "B.Paste")
			(net "FM_FAN_PWR_EN_R")
		)
		(pad "2" smd circle
			(at -0.40005 0 270)
			(size 0 0)
			(layers "B.Cu" "B.Mask" "B.Paste")
			(net "FM_FAN_PWR_EN")
		)
	)
	(footprint ""
		(layer "B.Cu")
		(at 346.754958 -269.30731 180)
		(property "Reference" "C2256"
			(at 0 0 0)
			(layer "B.SilkS")
			(hide yes)
			(effects
				(font
					(size 1.27 1.27)
				)
				(justify mirror)
			)
		)
		(property "Value" ""
			(at 0 0 0)
			(layer "B.Fab")
			(effects
				(font
					(size 1.27 1.27)
				)
				(justify mirror)
			)
		)
		(duplicate_pad_numbers_are_jumpers no)
		(fp_line
			(start 0.7874 0.4064)
			(end 0.7874 -0.4064)
			(stroke
				(width 0.1524)
				(type default)
			)
			(layer "B.SilkS")
		)
		(fp_line
			(start 0.7874 -0.4064)
			(end -0.7874 -0.4064)
			(stroke
				(width 0.1524)
				(type default)
			)
			(layer "B.SilkS")
		)
		(fp_line
			(start -0.7874 0.4064)
			(end 0.7874 0.4064)
			(stroke
				(width 0.1524)
				(type default)
			)
			(layer "B.SilkS")
		)
		(fp_line
			(start -0.7874 -0.4064)
			(end -0.7874 0.4064)
			(stroke
				(width 0.1524)
				(type default)
			)
			(layer "B.SilkS")
		)
		(fp_line
			(start 0.67945 0.3048)
			(end 0.67945 -0.305054)
			(stroke
				(width 0.1)
				(type default)
			)
			(layer "B.Fab")
		)
		(fp_line
			(start 0.67945 -0.305054)
			(end 0.12065 -0.305054)
			(stroke
				(width 0.1)
				(type default)
			)
			(layer "B.Fab")
		)
		(fp_line
			(start 0.12065 0.3048)
			(end 0.67945 0.3048)
			(stroke
				(width 0.1)
				(type default)
			)
			(layer "B.Fab")
		)
		(fp_line
			(start 0.12065 0.2794)
			(end 0.12065 0.3048)
			(stroke
				(width 0.1)
				(type default)
			)
			(layer "B.Fab")
		)
		(fp_line
			(start 0.12065 -0.2794)
			(end -0.12065 -0.2794)
			(stroke
				(width 0.1)
				(type default)
			)
			(layer "B.Fab")
		)
		(fp_line
			(start 0.12065 -0.305054)
			(end 0.12065 -0.2794)
			(stroke
				(width 0.1)
				(type default)
			)
			(layer "B.Fab")
		)
		(fp_line
			(start -0.120396 0.3048)
			(end -0.120396 0.2794)
			(stroke
				(width 0.1)
				(type default)
			)
			(layer "B.Fab")
		)
		(fp_line
			(start -0.120396 0.2794)
			(end 0.12065 0.2794)
			(stroke
				(width 0.1)
				(type default)
			)
			(layer "B.Fab")
		)
		(fp_line
			(start -0.12065 -0.2794)
			(end -0.12065 -0.3048)
			(stroke
				(width 0.1)
				(type default)
			)
			(layer "B.Fab")
		)
		(fp_line
			(start -0.12065 -0.3048)
			(end -0.67945 -0.3048)
			(stroke
				(width 0.1)
				(type default)
			)
			(layer "B.Fab")
		)
		(fp_line
			(start -0.67945 0.3048)
			(end -0.120396 0.3048)
			(stroke
				(width 0.1)
				(type default)
			)
			(layer "B.Fab")
		)
		(fp_line
			(start -0.67945 -0.3048)
			(end -0.67945 0.3048)
			(stroke
				(width 0.1)
				(type default)
			)
			(layer "B.Fab")
		)
		(pad "1" smd circle
			(at 0.40005 0)
			(size 0 0)
			(layers "B.Cu" "B.Mask" "B.Paste")
			(net "PVDDCR_CPU1_P0")
		)
		(pad "2" smd circle
			(at -0.40005 0)
			(size 0 0)
			(layers "B.Cu" "B.Mask" "B.Paste")
			(net "GND")
		)
	)
	(footprint ""
		(layer "B.Cu")
		(at 191.26454 -402.741892 90)
		(property "Reference" "R2587"
			(at 0 0 90)
			(layer "B.SilkS")
			(hide yes)
			(effects
				(font
					(size 1.27 1.27)
				)
				(justify mirror)
			)
		)
		(property "Value" ""
			(at 0 0 90)
			(layer "B.Fab")
			(effects
				(font
					(size 1.27 1.27)
				)
				(justify mirror)
			)
		)
		(duplicate_pad_numbers_are_jumpers no)
		(fp_line
			(start 0.7874 -0.4064)
			(end -0.7874 -0.4064)
			(stroke
				(width 0.1524)
				(type default)
			)
			(layer "B.SilkS")
		)
		(fp_line
			(start -0.7874 -0.4064)
			(end -0.7874 0.4064)
			(stroke
				(width 0.1524)
				(type default)
			)
			(layer "B.SilkS")
		)
		(fp_line
			(start 0.7874 0.4064)
			(end 0.7874 -0.4064)
			(stroke
				(width 0.1524)
				(type default)
			)
			(layer "B.SilkS")
		)
		(fp_line
			(start -0.7874 0.4064)
			(end 0.7874 0.4064)
			(stroke
				(width 0.1524)
				(type default)
			)
			(layer "B.SilkS")
		)
		(fp_line
			(start 0.67945 -0.305054)
			(end 0.12065 -0.305054)
			(stroke
				(width 0.1)
				(type default)
			)
			(layer "B.Fab")
		)
		(fp_line
			(start 0.12065 -0.305054)
			(end 0.12065 -0.2794)
			(stroke
				(width 0.1)
				(type default)
			)
			(layer "B.Fab")
		)
		(fp_line
			(start -0.12065 -0.3048)
			(end -0.67945 -0.3048)
			(stroke
				(width 0.1)
				(type default)
			)
			(layer "B.Fab")
		)
		(fp_line
			(start -0.67945 -0.3048)
			(end -0.67945 0.3048)
			(stroke
				(width 0.1)
				(type default)
			)
			(layer "B.Fab")
		)
		(fp_line
			(start 0.12065 -0.2794)
			(end -0.12065 -0.2794)
			(stroke
				(width 0.1)
				(type default)
			)
			(layer "B.Fab")
		)
		(fp_line
			(start -0.12065 -0.2794)
			(end -0.12065 -0.3048)
			(stroke
				(width 0.1)
				(type default)
			)
			(layer "B.Fab")
		)
		(fp_line
			(start 0.12065 0.2794)
			(end 0.12065 0.3048)
			(stroke
				(width 0.1)
				(type default)
			)
			(layer "B.Fab")
		)
		(fp_line
			(start -0.120396 0.2794)
			(end 0.12065 0.2794)
			(stroke
				(width 0.1)
				(type default)
			)
			(layer "B.Fab")
		)
		(fp_line
			(start 0.67945 0.3048)
			(end 0.67945 -0.305054)
			(stroke
				(width 0.1)
				(type default)
			)
			(layer "B.Fab")
		)
		(fp_line
			(start 0.12065 0.3048)
			(end 0.67945 0.3048)
			(stroke
				(width 0.1)
				(type default)
			)
			(layer "B.Fab")
		)
		(fp_line
			(start -0.120396 0.3048)
			(end -0.120396 0.2794)
			(stroke
				(width 0.1)
				(type default)
			)
			(layer "B.Fab")
		)
		(fp_line
			(start -0.67945 0.3048)
			(end -0.120396 0.3048)
			(stroke
				(width 0.1)
				(type default)
			)
			(layer "B.Fab")
		)
		(pad "1" smd circle
			(at 0.40005 0 270)
			(size 0 0)
			(layers "B.Cu" "B.Mask" "B.Paste")
			(net "IRQ_HSC_FAULT_N")
		)
		(pad "2" smd circle
			(at -0.40005 0 270)
			(size 0 0)
			(layers "B.Cu" "B.Mask" "B.Paste")
			(net "HSC_VDD")
		)
	)
	(footprint ""
		(layer "B.Cu")
		(at 167.31869 -14.462506 -90)
		(property "Reference" "R2995"
			(at 0 0 90)
			(layer "B.SilkS")
			(hide yes)
			(effects
				(font
					(size 1.27 1.27)
				)
				(justify mirror)
			)
		)
		(property "Value" ""
			(at 0 0 90)
			(layer "B.Fab")
			(effects
				(font
					(size 1.27 1.27)
				)
				(justify mirror)
			)
		)
		(duplicate_pad_numbers_are_jumpers no)
		(fp_line
			(start -0.7874 0.4064)
			(end 0.7874 0.4064)
			(stroke
				(width 0.1524)
				(type default)
			)
			(layer "B.SilkS")
		)
		(fp_line
			(start 0.7874 0.4064)
			(end 0.7874 -0.4064)
			(stroke
				(width 0.1524)
				(type default)
			)
			(layer "B.SilkS")
		)
		(fp_line
			(start -0.7874 -0.4064)
			(end -0.7874 0.4064)
			(stroke
				(width 0.1524)
				(type default)
			)
			(layer "B.SilkS")
		)
		(fp_line
			(start 0.7874 -0.4064)
			(end -0.7874 -0.4064)
			(stroke
				(width 0.1524)
				(type default)
			)
			(layer "B.SilkS")
		)
		(fp_line
			(start -0.67945 0.3048)
			(end -0.120396 0.3048)
			(stroke
				(width 0.1)
				(type default)
			)
			(layer "B.Fab")
		)
		(fp_line
			(start -0.120396 0.3048)
			(end -0.120396 0.2794)
			(stroke
				(width 0.1)
				(type default)
			)
			(layer "B.Fab")
		)
		(fp_line
			(start 0.12065 0.3048)
			(end 0.67945 0.3048)
			(stroke
				(width 0.1)
				(type default)
			)
			(layer "B.Fab")
		)
		(fp_line
			(start 0.67945 0.3048)
			(end 0.67945 -0.305054)
			(stroke
				(width 0.1)
				(type default)
			)
			(layer "B.Fab")
		)
		(fp_line
			(start -0.120396 0.2794)
			(end 0.12065 0.2794)
			(stroke
				(width 0.1)
				(type default)
			)
			(layer "B.Fab")
		)
		(fp_line
			(start 0.12065 0.2794)
			(end 0.12065 0.3048)
			(stroke
				(width 0.1)
				(type default)
			)
			(layer "B.Fab")
		)
		(fp_line
			(start -0.12065 -0.2794)
			(end -0.12065 -0.3048)
			(stroke
				(width 0.1)
				(type default)
			)
			(layer "B.Fab")
		)
		(fp_line
			(start 0.12065 -0.2794)
			(end -0.12065 -0.2794)
			(stroke
				(width 0.1)
				(type default)
			)
			(layer "B.Fab")
		)
		(fp_line
			(start -0.67945 -0.3048)
			(end -0.67945 0.3048)
			(stroke
				(width 0.1)
				(type default)
			)
			(layer "B.Fab")
		)
		(fp_line
			(start -0.12065 -0.3048)
			(end -0.67945 -0.3048)
			(stroke
				(width 0.1)
				(type default)
			)
			(layer "B.Fab")
		)
		(fp_line
			(start 0.12065 -0.305054)
			(end 0.12065 -0.2794)
			(stroke
				(width 0.1)
				(type default)
			)
			(layer "B.Fab")
		)
		(fp_line
			(start 0.67945 -0.305054)
			(end 0.12065 -0.305054)
			(stroke
				(width 0.1)
				(type default)
			)
			(layer "B.Fab")
		)
		(pad "1" smd circle
			(at 0.40005 0 90)
			(size 0 0)
			(layers "B.Cu" "B.Mask" "B.Paste")
			(net "SMB_PMBUS_3V3AUX_SCL")
		)
		(pad "2" smd circle
			(at -0.40005 0 90)
			(size 0 0)
			(layers "B.Cu" "B.Mask" "B.Paste")
			(net "SMB_SML1_PMBUS_HSC_SCL")
		)
	)
	(footprint ""
		(layer "B.Cu")
		(at 149.087586 -316.88405 90)
		(property "Reference" "Y4"
			(at 2.626106 1.482598 0)
			(unlocked yes)
			(layer "B.SilkS")
			(effects
				(font
					(size 0.7874 0.5842)
					(thickness 0.1524)
				)
				(justify left mirror)
			)
		)
		(property "Value" ""
			(at 0 0 90)
			(layer "B.Fab")
			(effects
				(font
					(size 1.27 1.27)
				)
				(justify mirror)
			)
		)
		(duplicate_pad_numbers_are_jumpers no)
		(fp_line
			(start 1.538732 -1.937004)
			(end -1.538732 -1.937004)
			(stroke
				(width 0.1524)
				(type default)
			)
			(layer "B.SilkS")
		)
		(fp_line
			(start -1.538732 -1.937004)
			(end -1.538732 1.937004)
			(stroke
				(width 0.1524)
				(type default)
			)
			(layer "B.SilkS")
		)
		(fp_line
			(start 1.538732 1.937004)
			(end 1.538732 -1.937004)
			(stroke
				(width 0.1524)
				(type default)
			)
			(layer "B.SilkS")
		)
		(fp_line
			(start -1.538732 1.937004)
			(end 1.538732 1.937004)
			(stroke
				(width 0.1524)
				(type default)
			)
			(layer "B.SilkS")
		)
		(fp_poly
			(pts
				(xy 2.251964 -1.24841) (xy 3.118358 -1.681734) (xy 3.118358 -0.81534)
			)
			(stroke
				(width 0)
				(type default)
			)
			(fill yes)
			(layer "B.SilkS")
		)
		(fp_line
			(start 1.299972 -1.649984)
			(end -1.299972 -1.649984)
			(stroke
				(width 0.1)
				(type default)
			)
			(layer "B.Fab")
		)
		(fp_line
			(start -1.299972 -1.649984)
			(end -1.299972 1.649984)
			(stroke
				(width 0.1)
				(type default)
			)
			(layer "B.Fab")
		)
		(fp_line
			(start 1.299972 1.649984)
			(end 1.299972 -1.649984)
			(stroke
				(width 0.1)
				(type default)
			)
			(layer "B.Fab")
		)
		(fp_line
			(start -1.299972 1.649984)
			(end 1.299972 1.649984)
			(stroke
				(width 0.1)
				(type default)
			)
			(layer "B.Fab")
		)
		(fp_poly
			(pts
				(xy 2.5908 -0.626872) (xy 2.5908 -1.493266) (xy 1.724406 -1.059942)
			)
			(stroke
				(width 0)
				(type default)
			)
			(fill yes)
			(layer "B.Fab")
		)
		(pad "1" smd rect
			(at 0.8001 -1.059942 270)
			(size 1.2192 1.4986)
			(layers "B.Cu" "B.Mask" "B.Paste")
			(net "XTAL_CPU1_X48M_X1")
		)
		(pad "2" smd rect
			(at 0.8001 1.059942 270)
			(size 1.2192 1.4986)
			(layers "B.Cu" "B.Mask" "B.Paste")
			(net "GND")
		)
		(pad "3" smd rect
			(at -0.8001 1.059942 270)
			(size 1.2192 1.4986)
			(layers "B.Cu" "B.Mask" "B.Paste")
			(net "XTAL_CPU1_X48M_X2_R")
		)
		(pad "4" smd rect
			(at -0.8001 -1.059942 270)
			(size 1.2192 1.4986)
			(layers "B.Cu" "B.Mask" "B.Paste")
			(net "GND")
		)
	)
)
